(kicad_pcb
	(version 20260206)
	(generator "pcbnew")
	(generator_version "10.0")
	(general
		(thickness 1.6)
		(legacy_teardrops no)
	)
	(paper "A4")
	(title_block
		(title "01162023_DA0F0TEBIF0_F0T_Expander_BD_F_brd_V02_OCP.brd")
		(comment 1 "Grand Teton / footprints 6095-6101 of 9728")
	)
	(layers
		(0 "F.Cu" signal "TOP")
		(4 "In1.Cu" signal "GND")
		(6 "In2.Cu" signal "VCC")
		(8 "In3.Cu" signal "VCC1")
		(10 "In4.Cu" signal "GND1")
		(12 "In5.Cu" signal "IN1")
		(14 "In6.Cu" signal "GND2")
		(16 "In7.Cu" signal "IN2")
		(18 "In8.Cu" signal "GND3")
		(20 "In9.Cu" signal "IN3")
		(22 "In10.Cu" signal "GND4")
		(24 "In11.Cu" signal "IN4")
		(26 "In12.Cu" signal "GND5")
		(28 "In13.Cu" signal "IN5")
		(30 "In14.Cu" signal "GND6")
		(32 "In15.Cu" signal "IN6")
		(34 "In16.Cu" signal "GND7")
		(2 "B.Cu" signal "BOTTOM")
		(9 "F.Adhes" user "F.Adhesive")
		(11 "B.Adhes" user "B.Adhesive")
		(13 "F.Paste" user "Package Geometry/Pastemask Top")
		(15 "B.Paste" user "Package Geometry/Pastemask Bottom")
		(5 "F.SilkS" user "Ref Des/Silkscreen Top")
		(7 "B.SilkS" user "Ref Des/Silkscreen Bottom")
		(1 "F.Mask" user "Board Geometry/Soldermask Top")
		(3 "B.Mask" user "Board Geometry/Soldermask Bottom")
		(17 "Dwgs.User" user "User.Drawings")
		(19 "Cmts.User" user "User.Comments")
		(21 "Eco1.User" user "User.Eco1")
		(23 "Eco2.User" user "User.Eco2")
		(25 "Edge.Cuts" user "Board Geometry/Outline")
		(27 "Margin" user)
		(31 "F.CrtYd" user "Package Geometry/Place Bound Top")
		(29 "B.CrtYd" user "Package Geometry/Place Bound Bottom")
		(35 "F.Fab" user "Ref Des/Assembly Top")
		(33 "B.Fab" user "Ref Des/Assembly Bottom")
	)
	(footprint ""
		(layer "F.Cu")
		(at 145.255234 -53.468524 90)
		(property "Reference" "PC521"
			(at 0 0 90)
			(layer "F.SilkS")
			(hide yes)
			(effects
				(font
					(size 1.27 1.27)
				)
			)
		)
		(property "Value" ""
			(at 0 0 90)
			(layer "F.Fab")
			(effects
				(font
					(size 1.27 1.27)
				)
			)
		)
		(duplicate_pad_numbers_are_jumpers no)
		(fp_line
			(start 1.524 -0.762)
			(end 1.524 0.762)
			(stroke
				(width 0.1524)
				(type default)
			)
			(layer "F.SilkS")
		)
		(fp_line
			(start -1.524 -0.762)
			(end 1.524 -0.762)
			(stroke
				(width 0.1524)
				(type default)
			)
			(layer "F.SilkS")
		)
		(fp_line
			(start 1.524 0.762)
			(end -1.524 0.762)
			(stroke
				(width 0.1524)
				(type default)
			)
			(layer "F.SilkS")
		)
		(fp_line
			(start -1.524 0.762)
			(end -1.524 -0.762)
			(stroke
				(width 0.1524)
				(type default)
			)
			(layer "F.SilkS")
		)
		(fp_line
			(start 1.1049 -0.724916)
			(end -1.1049 -0.724916)
			(stroke
				(width 0.1)
				(type default)
			)
			(layer "F.Fab")
		)
		(fp_line
			(start -1.1049 -0.724916)
			(end -1.1049 0.724916)
			(stroke
				(width 0.1)
				(type default)
			)
			(layer "F.Fab")
		)
		(fp_line
			(start 1.1049 0.724916)
			(end 1.1049 -0.724916)
			(stroke
				(width 0.1)
				(type default)
			)
			(layer "F.Fab")
		)
		(fp_line
			(start -1.1049 0.724916)
			(end 1.1049 0.724916)
			(stroke
				(width 0.1)
				(type default)
			)
			(layer "F.Fab")
		)
		(pad "1" smd rect
			(at -0.889 0 270)
			(size 1.016 1.27)
			(layers "F.Cu" "F.Mask" "F.Paste")
			(net "GND")
		)
		(pad "2" smd rect
			(at 0.889 0 270)
			(size 1.016 1.27)
			(layers "F.Cu" "F.Mask" "F.Paste")
			(net "P3V3_AUX")
		)
	)
	(footprint ""
		(layer "F.Cu")
		(at 353.695 -183.388)
		(property "Reference" "R4763"
			(at 0 0 0)
			(layer "F.SilkS")
			(hide yes)
			(effects
				(font
					(size 1.27 1.27)
				)
			)
		)
		(property "Value" ""
			(at 0 0 0)
			(layer "F.Fab")
			(effects
				(font
					(size 1.27 1.27)
				)
			)
		)
		(duplicate_pad_numbers_are_jumpers no)
		(fp_line
			(start -0.7874 -0.4064)
			(end 0.7874 -0.4064)
			(stroke
				(width 0.1524)
				(type default)
			)
			(layer "F.SilkS")
		)
		(fp_line
			(start -0.7874 0.4064)
			(end -0.7874 -0.4064)
			(stroke
				(width 0.1524)
				(type default)
			)
			(layer "F.SilkS")
		)
		(fp_line
			(start 0.7874 -0.4064)
			(end 0.7874 0.4064)
			(stroke
				(width 0.1524)
				(type default)
			)
			(layer "F.SilkS")
		)
		(fp_line
			(start 0.7874 0.4064)
			(end -0.7874 0.4064)
			(stroke
				(width 0.1524)
				(type default)
			)
			(layer "F.SilkS")
		)
		(fp_line
			(start -0.67945 -0.305054)
			(end -0.12065 -0.305054)
			(stroke
				(width 0.1)
				(type default)
			)
			(layer "F.Fab")
		)
		(fp_line
			(start -0.67945 0.3048)
			(end -0.67945 -0.305054)
			(stroke
				(width 0.1)
				(type default)
			)
			(layer "F.Fab")
		)
		(fp_line
			(start -0.12065 -0.305054)
			(end -0.12065 -0.2794)
			(stroke
				(width 0.1)
				(type default)
			)
			(layer "F.Fab")
		)
		(fp_line
			(start -0.12065 -0.2794)
			(end 0.12065 -0.2794)
			(stroke
				(width 0.1)
				(type default)
			)
			(layer "F.Fab")
		)
		(fp_line
			(start -0.12065 0.2794)
			(end -0.12065 0.3048)
			(stroke
				(width 0.1)
				(type default)
			)
			(layer "F.Fab")
		)
		(fp_line
			(start -0.12065 0.3048)
			(end -0.67945 0.3048)
			(stroke
				(width 0.1)
				(type default)
			)
			(layer "F.Fab")
		)
		(fp_line
			(start 0.120396 0.2794)
			(end -0.12065 0.2794)
			(stroke
				(width 0.1)
				(type default)
			)
			(layer "F.Fab")
		)
		(fp_line
			(start 0.120396 0.3048)
			(end 0.120396 0.2794)
			(stroke
				(width 0.1)
				(type default)
			)
			(layer "F.Fab")
		)
		(fp_line
			(start 0.12065 -0.3048)
			(end 0.67945 -0.3048)
			(stroke
				(width 0.1)
				(type default)
			)
			(layer "F.Fab")
		)
		(fp_line
			(start 0.12065 -0.2794)
			(end 0.12065 -0.3048)
			(stroke
				(width 0.1)
				(type default)
			)
			(layer "F.Fab")
		)
		(fp_line
			(start 0.67945 -0.3048)
			(end 0.67945 0.3048)
			(stroke
				(width 0.1)
				(type default)
			)
			(layer "F.Fab")
		)
		(fp_line
			(start 0.67945 0.3048)
			(end 0.120396 0.3048)
			(stroke
				(width 0.1)
				(type default)
			)
			(layer "F.Fab")
		)
		(pad "1" smd circle
			(at -0.40005 0)
			(size 0 0)
			(layers "F.Cu" "F.Mask" "F.Paste")
			(net "GND")
		)
		(pad "2" smd circle
			(at 0.40005 0)
			(size 0 0)
			(layers "F.Cu" "F.Mask" "F.Paste")
			(net "PCA9555_0_PEX2_A0")
		)
	)
	(footprint ""
		(layer "F.Cu")
		(at 32.657288 -350.098614 90)
		(property "Reference" "C180"
			(at 0 0 90)
			(layer "F.SilkS")
			(hide yes)
			(effects
				(font
					(size 1.27 1.27)
				)
			)
		)
		(property "Value" ""
			(at 0 0 90)
			(layer "F.Fab")
			(effects
				(font
					(size 1.27 1.27)
				)
			)
		)
		(duplicate_pad_numbers_are_jumpers no)
		(fp_line
			(start 0.299974 -0.150114)
			(end 0.299974 0.150114)
			(stroke
				(width 0.1)
				(type default)
			)
			(layer "F.Fab")
		)
		(fp_line
			(start -0.299974 -0.150114)
			(end 0.299974 -0.150114)
			(stroke
				(width 0.1)
				(type default)
			)
			(layer "F.Fab")
		)
		(fp_line
			(start 0.299974 0.150114)
			(end -0.299974 0.150114)
			(stroke
				(width 0.1)
				(type default)
			)
			(layer "F.Fab")
		)
		(fp_line
			(start -0.299974 0.150114)
			(end -0.299974 -0.150114)
			(stroke
				(width 0.1)
				(type default)
			)
			(layer "F.Fab")
		)
		(pad "1" smd rect
			(at -0.2667 0 90)
			(size 0.3048 0.381)
			(layers "F.Cu" "F.Mask" "F.Paste")
			(net "P5E_PEX0_STN7_TX_DN<118>")
		)
		(pad "2" smd rect
			(at 0.2667 0 90)
			(size 0.3048 0.381)
			(layers "F.Cu" "F.Mask" "F.Paste")
			(net "P5E_PEX0_STN7_TX_C_DN<118>")
		)
	)
	(footprint ""
		(layer "F.Cu")
		(at 219.825316 -123.774962)
		(property "Reference" "R5963"
			(at 0 0 0)
			(layer "F.SilkS")
			(hide yes)
			(effects
				(font
					(size 1.27 1.27)
				)
			)
		)
		(property "Value" ""
			(at 0 0 0)
			(layer "F.Fab")
			(effects
				(font
					(size 1.27 1.27)
				)
			)
		)
		(duplicate_pad_numbers_are_jumpers no)
		(fp_line
			(start -0.7874 -0.4064)
			(end 0.7874 -0.4064)
			(stroke
				(width 0.1524)
				(type default)
			)
			(layer "F.SilkS")
		)
		(fp_line
			(start -0.7874 0.4064)
			(end -0.7874 -0.4064)
			(stroke
				(width 0.1524)
				(type default)
			)
			(layer "F.SilkS")
		)
		(fp_line
			(start 0.7874 -0.4064)
			(end 0.7874 0.4064)
			(stroke
				(width 0.1524)
				(type default)
			)
			(layer "F.SilkS")
		)
		(fp_line
			(start 0.7874 0.4064)
			(end -0.7874 0.4064)
			(stroke
				(width 0.1524)
				(type default)
			)
			(layer "F.SilkS")
		)
		(fp_line
			(start -0.67945 -0.305054)
			(end -0.12065 -0.305054)
			(stroke
				(width 0.1)
				(type default)
			)
			(layer "F.Fab")
		)
		(fp_line
			(start -0.67945 0.3048)
			(end -0.67945 -0.305054)
			(stroke
				(width 0.1)
				(type default)
			)
			(layer "F.Fab")
		)
		(fp_line
			(start -0.12065 -0.305054)
			(end -0.12065 -0.2794)
			(stroke
				(width 0.1)
				(type default)
			)
			(layer "F.Fab")
		)
		(fp_line
			(start -0.12065 -0.2794)
			(end 0.12065 -0.2794)
			(stroke
				(width 0.1)
				(type default)
			)
			(layer "F.Fab")
		)
		(fp_line
			(start -0.12065 0.2794)
			(end -0.12065 0.3048)
			(stroke
				(width 0.1)
				(type default)
			)
			(layer "F.Fab")
		)
		(fp_line
			(start -0.12065 0.3048)
			(end -0.67945 0.3048)
			(stroke
				(width 0.1)
				(type default)
			)
			(layer "F.Fab")
		)
		(fp_line
			(start 0.120396 0.2794)
			(end -0.12065 0.2794)
			(stroke
				(width 0.1)
				(type default)
			)
			(layer "F.Fab")
		)
		(fp_line
			(start 0.120396 0.3048)
			(end 0.120396 0.2794)
			(stroke
				(width 0.1)
				(type default)
			)
			(layer "F.Fab")
		)
		(fp_line
			(start 0.12065 -0.3048)
			(end 0.67945 -0.3048)
			(stroke
				(width 0.1)
				(type default)
			)
			(layer "F.Fab")
		)
		(fp_line
			(start 0.12065 -0.2794)
			(end 0.12065 -0.3048)
			(stroke
				(width 0.1)
				(type default)
			)
			(layer "F.Fab")
		)
		(fp_line
			(start 0.67945 -0.3048)
			(end 0.67945 0.3048)
			(stroke
				(width 0.1)
				(type default)
			)
			(layer "F.Fab")
		)
		(fp_line
			(start 0.67945 0.3048)
			(end 0.120396 0.3048)
			(stroke
				(width 0.1)
				(type default)
			)
			(layer "F.Fab")
		)
		(pad "1" smd circle
			(at -0.40005 0)
			(size 0 0)
			(layers "F.Cu" "F.Mask" "F.Paste")
			(net "P3V3_NIC3")
		)
		(pad "2" smd circle
			(at 0.40005 0)
			(size 0 0)
			(layers "F.Cu" "F.Mask" "F.Paste")
			(net "P3V3_NIC3_PG_G1")
		)
	)
	(footprint ""
		(layer "F.Cu")
		(at 104.564942 -114.833654 -90)
		(property "Reference" "PC611"
			(at 0 0 270)
			(layer "F.SilkS")
			(hide yes)
			(effects
				(font
					(size 1.27 1.27)
				)
			)
		)
		(property "Value" ""
			(at 0 0 270)
			(layer "F.Fab")
			(effects
				(font
					(size 1.27 1.27)
				)
			)
		)
		(duplicate_pad_numbers_are_jumpers no)
		(fp_line
			(start -1.2954 0.5842)
			(end -1.2954 -0.5842)
			(stroke
				(width 0.1524)
				(type default)
			)
			(layer "F.SilkS")
		)
		(fp_line
			(start 1.2954 0.5842)
			(end -1.2954 0.5842)
			(stroke
				(width 0.1524)
				(type default)
			)
			(layer "F.SilkS")
		)
		(fp_line
			(start -1.2954 -0.5842)
			(end 1.2954 -0.5842)
			(stroke
				(width 0.1524)
				(type default)
			)
			(layer "F.SilkS")
		)
		(fp_line
			(start 1.2954 -0.5842)
			(end 1.2954 0.5842)
			(stroke
				(width 0.1524)
				(type default)
			)
			(layer "F.SilkS")
		)
		(fp_line
			(start -0.8636 0.4572)
			(end -0.8636 0.4064)
			(stroke
				(width 0.1)
				(type default)
			)
			(layer "F.Fab")
		)
		(fp_line
			(start 0.8636 0.4572)
			(end -0.8636 0.4572)
			(stroke
				(width 0.1)
				(type default)
			)
			(layer "F.Fab")
		)
		(fp_line
			(start -1.1938 0.4064)
			(end -1.1938 -0.4064)
			(stroke
				(width 0.1)
				(type default)
			)
			(layer "F.Fab")
		)
		(fp_line
			(start -0.8636 0.4064)
			(end -1.1938 0.4064)
			(stroke
				(width 0.1)
				(type default)
			)
			(layer "F.Fab")
		)
		(fp_line
			(start 0.8636 0.4064)
			(end 0.8636 0.4572)
			(stroke
				(width 0.1)
				(type default)
			)
			(layer "F.Fab")
		)
		(fp_line
			(start 1.1938 0.4064)
			(end 0.8636 0.4064)
			(stroke
				(width 0.1)
				(type default)
			)
			(layer "F.Fab")
		)
		(fp_line
			(start -1.1938 -0.4064)
			(end -0.8636 -0.4064)
			(stroke
				(width 0.1)
				(type default)
			)
			(layer "F.Fab")
		)
		(fp_line
			(start -0.8636 -0.4064)
			(end -0.8636 -0.4572)
			(stroke
				(width 0.1)
				(type default)
			)
			(layer "F.Fab")
		)
		(fp_line
			(start 0.8636 -0.4064)
			(end 1.1938 -0.4064)
			(stroke
				(width 0.1)
				(type default)
			)
			(layer "F.Fab")
		)
		(fp_line
			(start 1.1938 -0.4064)
			(end 1.1938 0.4064)
			(stroke
				(width 0.1)
				(type default)
			)
			(layer "F.Fab")
		)
		(fp_line
			(start -0.8636 -0.4572)
			(end 0.8636 -0.4572)
			(stroke
				(width 0.1)
				(type default)
			)
			(layer "F.Fab")
		)
		(fp_line
			(start 0.8636 -0.4572)
			(end 0.8636 -0.4064)
			(stroke
				(width 0.1)
				(type default)
			)
			(layer "F.Fab")
		)
		(pad "1" smd rect
			(at -0.7366 0 180)
			(size 0.7112 0.8128)
			(layers "F.Cu" "F.Mask" "F.Paste")
			(net "GND")
		)
		(pad "2" smd rect
			(at 0.7366 0 180)
			(size 0.7112 0.8128)
			(layers "F.Cu" "F.Mask" "F.Paste")
			(net "P12V_NIC1_CO_AVIN_PD")
		)
	)
	(footprint ""
		(layer "F.Cu")
		(at 241.075464 -218.80576)
		(property "Reference" "C3616"
			(at 0 0 0)
			(layer "F.SilkS")
			(hide yes)
			(effects
				(font
					(size 1.27 1.27)
				)
			)
		)
		(property "Value" ""
			(at 0 0 0)
			(layer "F.Fab")
			(effects
				(font
					(size 1.27 1.27)
				)
			)
		)
		(duplicate_pad_numbers_are_jumpers no)
		(fp_line
			(start -0.69215 -0.2921)
			(end 0.69215 -0.2921)
			(stroke
				(width 0.1524)
				(type default)
			)
			(layer "F.SilkS")
		)
		(fp_line
			(start -0.69215 0.2921)
			(end -0.69215 -0.2921)
			(stroke
				(width 0.1524)
				(type default)
			)
			(layer "F.SilkS")
		)
		(fp_line
			(start 0.69215 -0.2921)
			(end 0.69215 0.2921)
			(stroke
				(width 0.1524)
				(type default)
			)
			(layer "F.SilkS")
		)
		(fp_line
			(start 0.69215 0.2921)
			(end -0.69215 0.2921)
			(stroke
				(width 0.1524)
				(type default)
			)
			(layer "F.SilkS")
		)
		(fp_line
			(start -0.51435 -0.2794)
			(end 0.51435 -0.2794)
			(stroke
				(width 0.1)
				(type default)
			)
			(layer "F.Fab")
		)
		(fp_line
			(start -0.51435 0.2794)
			(end -0.51435 -0.2794)
			(stroke
				(width 0.1)
				(type default)
			)
			(layer "F.Fab")
		)
		(fp_line
			(start 0.51435 -0.2794)
			(end 0.51435 0.2794)
			(stroke
				(width 0.1)
				(type default)
			)
			(layer "F.Fab")
		)
		(fp_line
			(start 0.51435 0.2794)
			(end -0.51435 0.2794)
			(stroke
				(width 0.1)
				(type default)
			)
			(layer "F.Fab")
		)
		(pad "1" smd circle
			(at -0.40005 0)
			(size 0 0)
			(layers "F.Cu" "F.Mask" "F.Paste")
			(net "BIC_ADCVREFN0")
		)
		(pad "2" smd circle
			(at 0.40005 0)
			(size 0 0)
			(layers "F.Cu" "F.Mask" "F.Paste")
			(net "GND")
		)
		(zone
			(layer "F.Cu")
			(hatch none 0.5)
			(connect_pads
				(clearance 0)
			)
			(min_thickness 0.25)
			(keepout
				(tracks not_allowed)
				(vias allowed)
				(pads allowed)
				(copperpour not_allowed)
				(footprints allowed)
			)
			(placement
				(enabled no)
				(sheetname "")
			)
			(fill
				(thermal_gap 0.5)
				(thermal_bridge_width 0.5)
				(island_removal_mode 0)
			)
			(polygon
				(pts
					(xy 240.884964 -218.71813) (xy 240.976404 -218.659964) (xy 241.175794 -218.659964) (xy 241.265964 -218.71813)
					(xy 241.265964 -218.89339) (xy 241.175794 -218.95181) (xy 240.976404 -218.95181) (xy 240.884964 -218.893644)
				)
			)
		)
	)
	(footprint ""
		(layer "F.Cu")
		(at 279.774396 -414.88995 -90)
		(property "Reference" "R1809"
			(at 0 0 270)
			(layer "F.SilkS")
			(hide yes)
			(effects
				(font
					(size 1.27 1.27)
				)
			)
		)
		(property "Value" ""
			(at 0 0 270)
			(layer "F.Fab")
			(effects
				(font
					(size 1.27 1.27)
				)
			)
		)
		(duplicate_pad_numbers_are_jumpers no)
		(fp_line
			(start -0.7874 0.4064)
			(end -0.7874 -0.4064)
			(stroke
				(width 0.1524)
				(type default)
			)
			(layer "F.SilkS")
		)
		(fp_line
			(start 0.7874 0.4064)
			(end -0.7874 0.4064)
			(stroke
				(width 0.1524)
				(type default)
			)
			(layer "F.SilkS")
		)
		(fp_line
			(start -0.7874 -0.4064)
			(end 0.7874 -0.4064)
			(stroke
				(width 0.1524)
				(type default)
			)
			(layer "F.SilkS")
		)
		(fp_line
			(start 0.7874 -0.4064)
			(end 0.7874 0.4064)
			(stroke
				(width 0.1524)
				(type default)
			)
			(layer "F.SilkS")
		)
		(fp_line
			(start -0.67945 0.3048)
			(end -0.67945 -0.305054)
			(stroke
				(width 0.1)
				(type default)
			)
			(layer "F.Fab")
		)
		(fp_line
			(start -0.12065 0.3048)
			(end -0.67945 0.3048)
			(stroke
				(width 0.1)
				(type default)
			)
			(layer "F.Fab")
		)
		(fp_line
			(start 0.120396 0.3048)
			(end 0.120396 0.2794)
			(stroke
				(width 0.1)
				(type default)
			)
			(layer "F.Fab")
		)
		(fp_line
			(start 0.67945 0.3048)
			(end 0.120396 0.3048)
			(stroke
				(width 0.1)
				(type default)
			)
			(layer "F.Fab")
		)
		(fp_line
			(start -0.12065 0.2794)
			(end -0.12065 0.3048)
			(stroke
				(width 0.1)
				(type default)
			)
			(layer "F.Fab")
		)
		(fp_line
			(start 0.120396 0.2794)
			(end -0.12065 0.2794)
			(stroke
				(width 0.1)
				(type default)
			)
			(layer "F.Fab")
		)
		(fp_line
			(start -0.12065 -0.2794)
			(end 0.12065 -0.2794)
			(stroke
				(width 0.1)
				(type default)
			)
			(layer "F.Fab")
		)
		(fp_line
			(start 0.12065 -0.2794)
			(end 0.12065 -0.3048)
			(stroke
				(width 0.1)
				(type default)
			)
			(layer "F.Fab")
		)
		(fp_line
			(start 0.12065 -0.3048)
			(end 0.67945 -0.3048)
			(stroke
				(width 0.1)
				(type default)
			)
			(layer "F.Fab")
		)
		(fp_line
			(start 0.67945 -0.3048)
			(end 0.67945 0.3048)
			(stroke
				(width 0.1)
				(type default)
			)
			(layer "F.Fab")
		)
		(fp_line
			(start -0.67945 -0.305054)
			(end -0.12065 -0.305054)
			(stroke
				(width 0.1)
				(type default)
			)
			(layer "F.Fab")
		)
		(fp_line
			(start -0.12065 -0.305054)
			(end -0.12065 -0.2794)
			(stroke
				(width 0.1)
				(type default)
			)
			(layer "F.Fab")
		)
		(pad "1" smd circle
			(at -0.40005 0 270)
			(size 0 0)
			(layers "F.Cu" "F.Mask" "F.Paste")
			(net "P3V3_AUX")
		)
		(pad "2" smd circle
			(at 0.40005 0 270)
			(size 0 0)
			(layers "F.Cu" "F.Mask" "F.Paste")
			(net "MB_BIC_MON")
		)
	)
)
